(kicad_pcb
	(version 20260206)
	(generator "pcbnew")
	(generator_version "10.0")
	(general
		(thickness 1.6)
		(legacy_teardrops no)
	)
	(paper "A4")
	(title_block
		(title "Bryce Canyon_IOM_IOC_16318-2_OCP.brd")
		(comment 1 "Bryce Canyon / footprints 523-530 of 1605")
	)
	(layers
		(0 "F.Cu" signal "TOP")
		(4 "In1.Cu" signal "L2GND")
		(6 "In2.Cu" signal "L3")
		(8 "In3.Cu" signal "L4VCC")
		(10 "In4.Cu" signal "L5VCC")
		(12 "In5.Cu" signal "L6")
		(14 "In6.Cu" signal "L7GND")
		(2 "B.Cu" signal "BOTTOM")
		(9 "F.Adhes" user "F.Adhesive")
		(11 "B.Adhes" user "B.Adhesive")
		(13 "F.Paste" user "Package Geometry/Pastemask Top")
		(15 "B.Paste" user "Package Geometry/Pastemask Bottom")
		(5 "F.SilkS" user "Ref Des/Silkscreen Top")
		(7 "B.SilkS" user "Ref Des/Silkscreen Bottom")
		(1 "F.Mask" user "Board Geometry/Soldermask Top")
		(3 "B.Mask" user "Board Geometry/Soldermask Bottom")
		(17 "Dwgs.User" user "User.Drawings")
		(19 "Cmts.User" user "User.Comments")
		(21 "Eco1.User" user "User.Eco1")
		(23 "Eco2.User" user "User.Eco2")
		(25 "Edge.Cuts" user "Board Geometry/Outline")
		(27 "Margin" user)
		(31 "F.CrtYd" user "Package Geometry/Place Bound Top")
		(29 "B.CrtYd" user "Package Geometry/Place Bound Bottom")
		(35 "F.Fab" user "Ref Des/Assembly Top")
		(33 "B.Fab" user "Ref Des/Assembly Bottom")
	)
	(footprint ""
		(layer "F.Cu")
		(at 85.344 -150.368 90)
		(property "Reference" "C44"
			(at 0 0 90)
			(layer "F.SilkS")
			(hide yes)
			(effects
				(font
					(size 1.27 1.27)
				)
			)
		)
		(property "Value" "SCD1U16V2KX-3GP"
			(at 1.1811 -2.7051 90)
			(unlocked yes)
			(layer "F.Fab")
			(hide yes)
			(effects
				(font
					(size 1.016 1.016)
					(thickness 0.1524)
				)
			)
		)
		(property "Device Type" "C402H22"
			(at 1.1811 -4.2291 90)
			(unlocked yes)
			(layer "F.Fab")
			(hide yes)
			(effects
				(font
					(size 1.016 1.016)
					(thickness 0.1524)
				)
			)
		)
		(duplicate_pad_numbers_are_jumpers no)
		(fp_rect
			(start -0.4318 0.9525)
			(end 0.4318 -0.9525)
			(stroke
				(width 0)
				(type default)
			)
			(fill no)
			(layer "F.CrtYd")
		)
		(fp_rect
			(start -0.4318 0.9525)
			(end 0.4318 -0.9525)
			(stroke
				(width 0)
				(type default)
			)
			(fill no)
			(layer "F.Fab")
		)
		(pad "1" smd custom
			(at 0 -0.4445 90)
			(size 0.1524 0.1524)
			(layers "F.Cu" "F.Mask" "F.Paste")
			(net "P3V3_STBY")
			(options
				(clearance outline)
				(anchor circle)
			)
			(primitives
				(gr_poly
					(pts
						(arc
							(start 0.3048 -0.2032)
							(mid 0.275042 -0.275042)
							(end 0.2032 -0.3048)
						)
						(arc
							(start -0.2032 -0.3048)
							(mid -0.275042 -0.275042)
							(end -0.3048 -0.2032)
						)
						(arc
							(start -0.3048 0.2032)
							(mid -0.275042 0.275042)
							(end -0.2032 0.3048)
						)
						(arc
							(start 0.2032 0.3048)
							(mid 0.275042 0.275042)
							(end 0.3048 0.2032)
						)
					)
					(width 0)
					(fill yes)
				)
			)
		)
		(pad "2" smd custom
			(at 0 0.4445 90)
			(size 0.1524 0.1524)
			(layers "F.Cu" "F.Mask" "F.Paste")
			(net "GND")
			(options
				(clearance outline)
				(anchor circle)
			)
			(primitives
				(gr_poly
					(pts
						(arc
							(start 0.3048 -0.2032)
							(mid 0.275042 -0.275042)
							(end 0.2032 -0.3048)
						)
						(arc
							(start -0.2032 -0.3048)
							(mid -0.275042 -0.275042)
							(end -0.3048 -0.2032)
						)
						(arc
							(start -0.3048 0.2032)
							(mid -0.275042 0.275042)
							(end -0.2032 0.3048)
						)
						(arc
							(start 0.2032 0.3048)
							(mid 0.275042 0.275042)
							(end 0.3048 0.2032)
						)
					)
					(width 0)
					(fill yes)
				)
			)
		)
	)
	(footprint ""
		(layer "F.Cu")
		(at 155.758642 -95.053658)
		(property "Reference" "R692"
			(at 0 0 0)
			(layer "F.SilkS")
			(hide yes)
			(effects
				(font
					(size 1.27 1.27)
				)
			)
		)
		(property "Value" "0R2J-2-GP"
			(at 0.064008 -3.993896 0)
			(unlocked yes)
			(layer "F.Fab")
			(hide yes)
			(effects
				(font
					(size 1.016 1.016)
					(thickness 0.1524)
				)
			)
		)
		(property "Device Type" "R402H16"
			(at 0.064008 -5.517896 0)
			(unlocked yes)
			(layer "F.Fab")
			(hide yes)
			(effects
				(font
					(size 1.016 1.016)
					(thickness 0.1524)
				)
			)
		)
		(duplicate_pad_numbers_are_jumpers no)
		(fp_line
			(start -0.508 -0.9398)
			(end -0.508 0.9398)
			(stroke
				(width 0.1524)
				(type default)
			)
			(layer "F.SilkS")
		)
		(fp_line
			(start 0.508 -0.9398)
			(end -0.508 -0.9398)
			(stroke
				(width 0.1524)
				(type default)
			)
			(layer "F.SilkS")
		)
		(fp_rect
			(start -0.508 0.9398)
			(end 0.508 -0.9398)
			(stroke
				(width 0)
				(type default)
			)
			(fill no)
			(layer "F.CrtYd")
		)
		(fp_rect
			(start -0.508 0.9398)
			(end 0.508 -0.9398)
			(stroke
				(width 0)
				(type default)
			)
			(fill no)
			(layer "F.Fab")
		)
		(pad "1" smd custom
			(at 0 -0.4445)
			(size 0.1397 0.1397)
			(layers "F.Cu" "F.Mask" "F.Paste")
			(net "IOM_IOC_UART_TX")
			(options
				(clearance outline)
				(anchor circle)
			)
			(primitives
				(gr_poly
					(pts
						(arc
							(start -0.1778 -0.2794)
							(mid -0.249642 -0.249642)
							(end -0.2794 -0.1778)
						)
						(arc
							(start -0.2794 0.1778)
							(mid -0.249642 0.249642)
							(end -0.1778 0.2794)
						)
						(arc
							(start 0.1778 0.2794)
							(mid 0.249642 0.249642)
							(end 0.2794 0.1778)
						)
						(arc
							(start 0.2794 -0.1778)
							(mid 0.249642 -0.249642)
							(end 0.1778 -0.2794)
						)
					)
					(width 0)
					(fill yes)
				)
			)
		)
		(pad "2" smd custom
			(at 0 0.4445)
			(size 0.1397 0.1397)
			(layers "F.Cu" "F.Mask" "F.Paste")
			(net "IOC_UART_R_TX")
			(options
				(clearance outline)
				(anchor circle)
			)
			(primitives
				(gr_poly
					(pts
						(arc
							(start -0.1778 -0.2794)
							(mid -0.249642 -0.249642)
							(end -0.2794 -0.1778)
						)
						(arc
							(start -0.2794 0.1778)
							(mid -0.249642 0.249642)
							(end -0.1778 0.2794)
						)
						(arc
							(start 0.1778 0.2794)
							(mid 0.249642 0.249642)
							(end 0.2794 0.1778)
						)
						(arc
							(start 0.2794 -0.1778)
							(mid 0.249642 -0.249642)
							(end 0.1778 -0.2794)
						)
					)
					(width 0)
					(fill yes)
				)
			)
		)
	)
	(footprint ""
		(layer "F.Cu")
		(at 200.1266 -49.9618 -90)
		(property "Reference" "TP137"
			(at 0 0 270)
			(layer "F.SilkS")
			(hide yes)
			(effects
				(font
					(size 1.27 1.27)
				)
			)
		)
		(property "Value" "TPAD28-2-GP"
			(at -0.0127 -1.6637 270)
			(unlocked yes)
			(layer "F.Fab")
			(hide yes)
			(effects
				(font
					(size 1.016 1.016)
					(thickness 0.1524)
				)
			)
		)
		(property "Device Type" "TPAD28"
			(at -0.0127 -3.1877 270)
			(unlocked yes)
			(layer "F.Fab")
			(hide yes)
			(effects
				(font
					(size 1.016 1.016)
					(thickness 0.1524)
				)
			)
		)
		(duplicate_pad_numbers_are_jumpers no)
		(fp_poly
			(pts
				(arc
					(start 0 -0.3556)
					(mid 0 0.3556)
					(end 0 -0.3556)
				)
			)
			(stroke
				(width 0)
				(type default)
			)
			(fill no)
			(layer "F.CrtYd")
		)
		(fp_poly
			(pts
				(arc
					(start 0 -0.6096)
					(mid 0 0.6096)
					(end 0 -0.6096)
				)
			)
			(stroke
				(width 0)
				(type default)
			)
			(fill no)
			(layer "F.Fab")
		)
		(pad "1" smd circle
			(at 0 0 270)
			(size 0.7112 0.7112)
			(layers "F.Cu" "F.Mask" "F.Paste")
			(net "ICE0_TDI")
		)
	)
	(footprint ""
		(layer "F.Cu")
		(at 112.87379 -7.736078 -90)
		(property "Reference" "R459"
			(at 0 0 270)
			(layer "F.SilkS")
			(hide yes)
			(effects
				(font
					(size 1.27 1.27)
				)
			)
		)
		(property "Value" "0R2J-2-GP"
			(at 0.064008 -3.993896 270)
			(unlocked yes)
			(layer "F.Fab")
			(hide yes)
			(effects
				(font
					(size 1.016 1.016)
					(thickness 0.1524)
				)
			)
		)
		(property "Device Type" "R402H16"
			(at 0.064008 -5.517896 270)
			(unlocked yes)
			(layer "F.Fab")
			(hide yes)
			(effects
				(font
					(size 1.016 1.016)
					(thickness 0.1524)
				)
			)
		)
		(duplicate_pad_numbers_are_jumpers no)
		(fp_line
			(start -0.508 -0.9398)
			(end -0.508 0.9398)
			(stroke
				(width 0.1524)
				(type default)
			)
			(layer "F.SilkS")
		)
		(fp_line
			(start 0.508 -0.9398)
			(end -0.508 -0.9398)
			(stroke
				(width 0.1524)
				(type default)
			)
			(layer "F.SilkS")
		)
		(fp_rect
			(start -0.508 0.9398)
			(end 0.508 -0.9398)
			(stroke
				(width 0)
				(type default)
			)
			(fill no)
			(layer "F.CrtYd")
		)
		(fp_rect
			(start -0.508 0.9398)
			(end 0.508 -0.9398)
			(stroke
				(width 0)
				(type default)
			)
			(fill no)
			(layer "F.Fab")
		)
		(pad "1" smd custom
			(at 0 -0.4445 270)
			(size 0.1397 0.1397)
			(layers "F.Cu" "F.Mask" "F.Paste")
			(net "MB0_CM_ADR1_R")
			(options
				(clearance outline)
				(anchor circle)
			)
			(primitives
				(gr_poly
					(pts
						(arc
							(start -0.1778 -0.2794)
							(mid -0.249642 -0.249642)
							(end -0.2794 -0.1778)
						)
						(arc
							(start -0.2794 0.1778)
							(mid -0.249642 0.249642)
							(end -0.1778 0.2794)
						)
						(arc
							(start 0.1778 0.2794)
							(mid 0.249642 0.249642)
							(end 0.2794 0.1778)
						)
						(arc
							(start 0.2794 -0.1778)
							(mid 0.249642 -0.249642)
							(end 0.1778 -0.2794)
						)
					)
					(width 0)
					(fill yes)
				)
			)
		)
		(pad "2" smd custom
			(at 0 0.4445 270)
			(size 0.1397 0.1397)
			(layers "F.Cu" "F.Mask" "F.Paste")
			(net "AGND_CURRENT_MON")
			(options
				(clearance outline)
				(anchor circle)
			)
			(primitives
				(gr_poly
					(pts
						(arc
							(start -0.1778 -0.2794)
							(mid -0.249642 -0.249642)
							(end -0.2794 -0.1778)
						)
						(arc
							(start -0.2794 0.1778)
							(mid -0.249642 0.249642)
							(end -0.1778 0.2794)
						)
						(arc
							(start 0.1778 0.2794)
							(mid 0.249642 0.249642)
							(end 0.2794 0.1778)
						)
						(arc
							(start 0.2794 -0.1778)
							(mid 0.249642 -0.249642)
							(end 0.1778 -0.2794)
						)
					)
					(width 0)
					(fill yes)
				)
			)
		)
	)
	(footprint ""
		(layer "F.Cu")
		(at 155.42514 -132.471922 -90)
		(property "Reference" "C210"
			(at 0 0 270)
			(layer "F.SilkS")
			(hide yes)
			(effects
				(font
					(size 1.27 1.27)
				)
			)
		)
		(property "Value" "SC2200P50V2KX-2GP"
			(at 1.1811 -2.7051 270)
			(unlocked yes)
			(layer "F.Fab")
			(hide yes)
			(effects
				(font
					(size 1.016 1.016)
					(thickness 0.1524)
				)
			)
		)
		(property "Device Type" "C402H22"
			(at 1.1811 -4.2291 270)
			(unlocked yes)
			(layer "F.Fab")
			(hide yes)
			(effects
				(font
					(size 1.016 1.016)
					(thickness 0.1524)
				)
			)
		)
		(duplicate_pad_numbers_are_jumpers no)
		(fp_rect
			(start -0.4318 0.9525)
			(end 0.4318 -0.9525)
			(stroke
				(width 0)
				(type default)
			)
			(fill no)
			(layer "F.CrtYd")
		)
		(fp_rect
			(start -0.4318 0.9525)
			(end 0.4318 -0.9525)
			(stroke
				(width 0)
				(type default)
			)
			(fill no)
			(layer "F.Fab")
		)
		(pad "1" smd custom
			(at 0 -0.4445 270)
			(size 0.1524 0.1524)
			(layers "F.Cu" "F.Mask" "F.Paste")
			(net "P1V8_STBY_SW")
			(options
				(clearance outline)
				(anchor circle)
			)
			(primitives
				(gr_poly
					(pts
						(arc
							(start 0.3048 -0.2032)
							(mid 0.275042 -0.275042)
							(end 0.2032 -0.3048)
						)
						(arc
							(start -0.2032 -0.3048)
							(mid -0.275042 -0.275042)
							(end -0.3048 -0.2032)
						)
						(arc
							(start -0.3048 0.2032)
							(mid -0.275042 0.275042)
							(end -0.2032 0.3048)
						)
						(arc
							(start 0.2032 0.3048)
							(mid 0.275042 0.275042)
							(end 0.3048 0.2032)
						)
					)
					(width 0)
					(fill yes)
				)
			)
		)
		(pad "2" smd custom
			(at 0 0.4445 270)
			(size 0.1524 0.1524)
			(layers "F.Cu" "F.Mask" "F.Paste")
			(net "P1V8_STBY_SNB")
			(options
				(clearance outline)
				(anchor circle)
			)
			(primitives
				(gr_poly
					(pts
						(arc
							(start 0.3048 -0.2032)
							(mid 0.275042 -0.275042)
							(end 0.2032 -0.3048)
						)
						(arc
							(start -0.2032 -0.3048)
							(mid -0.275042 -0.275042)
							(end -0.3048 -0.2032)
						)
						(arc
							(start -0.3048 0.2032)
							(mid -0.275042 0.275042)
							(end -0.2032 0.3048)
						)
						(arc
							(start 0.2032 0.3048)
							(mid 0.275042 0.275042)
							(end 0.3048 0.2032)
						)
					)
					(width 0)
					(fill yes)
				)
			)
		)
	)
	(footprint ""
		(layer "F.Cu")
		(at 8.88111 -135.290052 -90)
		(property "Reference" "R239"
			(at 0 0 270)
			(layer "F.SilkS")
			(hide yes)
			(effects
				(font
					(size 1.27 1.27)
				)
			)
		)
		(property "Value" "0R2J-2-GP"
			(at 0.064008 -3.993896 270)
			(unlocked yes)
			(layer "F.Fab")
			(hide yes)
			(effects
				(font
					(size 1.016 1.016)
					(thickness 0.1524)
				)
			)
		)
		(property "Device Type" "R402H16"
			(at 0.064008 -5.517896 270)
			(unlocked yes)
			(layer "F.Fab")
			(hide yes)
			(effects
				(font
					(size 1.016 1.016)
					(thickness 0.1524)
				)
			)
		)
		(duplicate_pad_numbers_are_jumpers no)
		(fp_line
			(start -0.508 -0.9398)
			(end -0.508 0.9398)
			(stroke
				(width 0.1524)
				(type default)
			)
			(layer "F.SilkS")
		)
		(fp_line
			(start 0.508 -0.9398)
			(end -0.508 -0.9398)
			(stroke
				(width 0.1524)
				(type default)
			)
			(layer "F.SilkS")
		)
		(fp_rect
			(start -0.508 0.9398)
			(end 0.508 -0.9398)
			(stroke
				(width 0)
				(type default)
			)
			(fill no)
			(layer "F.CrtYd")
		)
		(fp_rect
			(start -0.508 0.9398)
			(end 0.508 -0.9398)
			(stroke
				(width 0)
				(type default)
			)
			(fill no)
			(layer "F.Fab")
		)
		(pad "1" smd custom
			(at 0 -0.4445 270)
			(size 0.1397 0.1397)
			(layers "F.Cu" "F.Mask" "F.Paste")
			(net "MEM_PAR")
			(options
				(clearance outline)
				(anchor circle)
			)
			(primitives
				(gr_poly
					(pts
						(arc
							(start -0.1778 -0.2794)
							(mid -0.249642 -0.249642)
							(end -0.2794 -0.1778)
						)
						(arc
							(start -0.2794 0.1778)
							(mid -0.249642 0.249642)
							(end -0.1778 0.2794)
						)
						(arc
							(start 0.1778 0.2794)
							(mid 0.249642 0.249642)
							(end 0.2794 0.1778)
						)
						(arc
							(start 0.2794 -0.1778)
							(mid 0.249642 -0.249642)
							(end 0.1778 -0.2794)
						)
					)
					(width 0)
					(fill yes)
				)
			)
		)
		(pad "2" smd custom
			(at 0 0.4445 270)
			(size 0.1397 0.1397)
			(layers "F.Cu" "F.Mask" "F.Paste")
			(net "GND")
			(options
				(clearance outline)
				(anchor circle)
			)
			(primitives
				(gr_poly
					(pts
						(arc
							(start -0.1778 -0.2794)
							(mid -0.249642 -0.249642)
							(end -0.2794 -0.1778)
						)
						(arc
							(start -0.2794 0.1778)
							(mid -0.249642 0.249642)
							(end -0.1778 0.2794)
						)
						(arc
							(start 0.1778 0.2794)
							(mid 0.249642 0.249642)
							(end 0.2794 0.1778)
						)
						(arc
							(start 0.2794 -0.1778)
							(mid 0.249642 -0.249642)
							(end 0.1778 -0.2794)
						)
					)
					(width 0)
					(fill yes)
				)
			)
		)
	)
	(footprint ""
		(layer "F.Cu")
		(at 164.6936 -138.4554 90)
		(property "Reference" "R511"
			(at 0 0 90)
			(layer "F.SilkS")
			(hide yes)
			(effects
				(font
					(size 1.27 1.27)
				)
			)
		)
		(property "Value" "2D2R3-1-U-GP"
			(at -0.0254 -2.5146 90)
			(unlocked yes)
			(layer "F.Fab")
			(hide yes)
			(effects
				(font
					(size 1.016 1.016)
					(thickness 0.1524)
				)
			)
		)
		(property "Device Type" "R603H22"
			(at -0.0254 -4.0386 90)
			(unlocked yes)
			(layer "F.Fab")
			(hide yes)
			(effects
				(font
					(size 1.016 1.016)
					(thickness 0.1524)
				)
			)
		)
		(duplicate_pad_numbers_are_jumpers no)
		(fp_line
			(start 0.2032 0)
			(end 0.4826 0)
			(stroke
				(width 0.2032)
				(type default)
			)
			(layer "F.SilkS")
		)
		(fp_line
			(start -0.4826 0)
			(end -0.2032 0)
			(stroke
				(width 0.2032)
				(type default)
			)
			(layer "F.SilkS")
		)
		(fp_rect
			(start -0.5842 1.3335)
			(end 0.5842 -1.3335)
			(stroke
				(width 0)
				(type default)
			)
			(fill no)
			(layer "F.CrtYd")
		)
		(fp_rect
			(start -0.5842 1.3335)
			(end 0.5842 -1.3335)
			(stroke
				(width 0)
				(type default)
			)
			(fill no)
			(layer "F.Fab")
		)
		(pad "1" smd custom
			(at 0 -0.762 90)
			(size 0.2159 0.2159)
			(layers "F.Cu" "F.Mask" "F.Paste")
			(net "P12V_STBY_VCC_PU4")
			(options
				(clearance outline)
				(anchor circle)
			)
			(primitives
				(gr_poly
					(pts
						(arc
							(start -0.3302 -0.4318)
							(mid -0.402042 -0.402042)
							(end -0.4318 -0.3302)
						)
						(arc
							(start -0.4318 0.3302)
							(mid -0.402042 0.402042)
							(end -0.3302 0.4318)
						)
						(arc
							(start 0.3302 0.4318)
							(mid 0.402042 0.402042)
							(end 0.4318 0.3302)
						)
						(arc
							(start 0.4318 -0.3302)
							(mid 0.402042 -0.402042)
							(end 0.3302 -0.4318)
						)
					)
					(width 0)
					(fill yes)
				)
			)
		)
		(pad "2" smd custom
			(at 0 0.762 90)
			(size 0.2159 0.2159)
			(layers "F.Cu" "F.Mask" "F.Paste")
			(net "P12V_STBY")
			(options
				(clearance outline)
				(anchor circle)
			)
			(primitives
				(gr_poly
					(pts
						(arc
							(start -0.3302 -0.4318)
							(mid -0.402042 -0.402042)
							(end -0.4318 -0.3302)
						)
						(arc
							(start -0.4318 0.3302)
							(mid -0.402042 0.402042)
							(end -0.3302 0.4318)
						)
						(arc
							(start 0.3302 0.4318)
							(mid 0.402042 0.402042)
							(end 0.4318 0.3302)
						)
						(arc
							(start 0.4318 -0.3302)
							(mid 0.402042 -0.402042)
							(end 0.3302 -0.4318)
						)
					)
					(width 0)
					(fill yes)
				)
			)
		)
	)
	(footprint ""
		(layer "F.Cu")
		(at 52.832 -132.207)
		(property "Reference" "TP10"
			(at 0 0 0)
			(layer "F.SilkS")
			(hide yes)
			(effects
				(font
					(size 1.27 1.27)
				)
			)
		)
		(property "Value" "TPAD28-2-GP"
			(at -0.0127 -1.6637 0)
			(unlocked yes)
			(layer "F.Fab")
			(hide yes)
			(effects
				(font
					(size 1.016 1.016)
					(thickness 0.1524)
				)
			)
		)
		(property "Device Type" "TPAD28"
			(at -0.0127 -3.1877 0)
			(unlocked yes)
			(layer "F.Fab")
			(hide yes)
			(effects
				(font
					(size 1.016 1.016)
					(thickness 0.1524)
				)
			)
		)
		(duplicate_pad_numbers_are_jumpers no)
		(fp_poly
			(pts
				(arc
					(start 0.3556 0)
					(mid -0.3556 0)
					(end 0.3556 0)
				)
			)
			(stroke
				(width 0)
				(type default)
			)
			(fill no)
			(layer "F.CrtYd")
		)
		(fp_poly
			(pts
				(arc
					(start 0.6096 0)
					(mid -0.6096 0)
					(end 0.6096 0)
				)
			)
			(stroke
				(width 0)
				(type default)
			)
			(fill no)
			(layer "F.Fab")
		)
		(pad "1" smd circle
			(at 0 0)
			(size 0.7112 0.7112)
			(layers "F.Cu" "F.Mask" "F.Paste")
			(net "TP_BMC0_LPC_LAD1")
		)
	)
)
